(kicad_pcb
	(version 20241229)
	(generator "pcbnew")
	(generator_version "9.0")
	(general
		(thickness 1.61)
		(legacy_teardrops no)
	)
	(paper "A3")
	(title_block
		(title "SO-DIMM DDR5 Tester")
		(date "2025-11-26")
		(rev "1.3.0")
		(comment 9 "footprints 267-268 of 627")
	)
	(layers
		(0 "F.Cu" signal)
		(4 "In1.Cu" power)
		(6 "In2.Cu" mixed)
		(8 "In3.Cu" power)
		(10 "In4.Cu" mixed)
		(12 "In5.Cu" power)
		(14 "In6.Cu" mixed)
		(16 "In7.Cu" power)
		(18 "In8.Cu" power)
		(20 "In9.Cu" mixed)
		(22 "In10.Cu" power)
		(2 "B.Cu" signal)
		(9 "F.Adhes" user "F.Adhesive")
		(11 "B.Adhes" user "B.Adhesive")
		(13 "F.Paste" user)
		(15 "B.Paste" user)
		(5 "F.SilkS" user "F.Silkscreen")
		(7 "B.SilkS" user "B.Silkscreen")
		(1 "F.Mask" user)
		(3 "B.Mask" user)
		(17 "Dwgs.User" user "User.Drawings")
		(19 "Cmts.User" user "User.Comments")
		(21 "Eco1.User" user "User.Eco1")
		(23 "Eco2.User" user "User.Eco2")
		(25 "Edge.Cuts" user)
		(27 "Margin" user)
		(31 "F.CrtYd" user "F.Courtyard")
		(29 "B.CrtYd" user "B.Courtyard")
		(35 "F.Fab" user)
		(33 "B.Fab" user)
	)
	(footprint "antmicro-footprints:SW_DIP_SPSTx08_Slide_Copal_CVS-08xB_W5.9mm_P1mm"
		(layer "F.Cu")
		(at 202.1285 153.3035)
		(descr "SMD 8x-dip-switch SPST Copal_CVS-08xB, Slide, row spacing 5.9 mm (232 mils), body size  (see http://www.nidec-copal-electronics.com/e/catalog/switch/cvs.pdf)")
		(tags "SMD DIP Switch SPST Slide 5.9mm 232mil")
		(property "Reference" "SW4"
			(at 1.3715 5.8965 0)
			(layer "F.SilkS")
			(effects
				(font
					(size 0.7 0.7)
					(thickness 0.15)
				)
				(justify left bottom)
			)
		)
		(property "Value" "SW_CVS-08TB"
			(at -14.59 6.29 0)
			(layer "F.Fab")
			(effects
				(font
					(size 0.7 0.7)
					(thickness 0.15)
				)
				(justify left bottom)
			)
		)
		(property "Datasheet" "https://www.mouser.com/datasheet/2/972/cvs-1827291.pdf"
			(at 0 0 0)
			(layer "F.Fab")
			(hide yes)
			(effects
				(font
					(size 1.27 1.27)
					(thickness 0.15)
				)
			)
		)
		(property "Author" "Antmicro"
			(at 0 0 0)
			(layer "F.Fab")
			(hide yes)
			(effects
				(font
					(size 1 1)
					(thickness 0.15)
				)
			)
		)
		(property "License" "Apache-2.0"
			(at 0 0 0)
			(layer "F.Fab")
			(hide yes)
			(effects
				(font
					(size 1 1)
					(thickness 0.15)
				)
			)
		)
		(property "MPN" "CVS-08TB"
			(at 0 0 0)
			(layer "F.Fab")
			(hide yes)
			(effects
				(font
					(size 1 1)
					(thickness 0.15)
				)
			)
		)
		(property "Manufacturer" "Nidec Components"
			(at 0 0 0)
			(layer "F.Fab")
			(hide yes)
			(effects
				(font
					(size 1 1)
					(thickness 0.15)
				)
			)
		)
		(property ki_fp_filters "SW?DIP?x2*")
		(sheetname "/Supply/")
		(sheetfile "supply.kicad_sch")
		(attr smd)
		(fp_line
			(start -1.561 -4.912)
			(end 1.56 -4.912)
			(stroke
				(width 0.15)
				(type solid)
			)
			(layer "F.SilkS")
		)
		(fp_line
			(start -1.561 4.91)
			(end 1.56 4.91)
			(stroke
				(width 0.15)
				(type solid)
			)
			(layer "F.SilkS")
		)
		(fp_circle
			(center -3.31 -4.2)
			(end -3.261 -4.2)
			(stroke
				(width 0.15)
				(type solid)
			)
			(fill yes)
			(layer "F.SilkS")
		)
		(fp_rect
			(start -3.601 -5)
			(end 3.598 4.998)
			(stroke
				(width 0.05)
				(type solid)
			)
			(fill no)
			(layer "F.CrtYd")
		)
		(fp_line
			(start -2.351 -3.5)
			(end -1.351 -4.5)
			(stroke
				(width 0.15)
				(type solid)
			)
			(layer "F.Fab")
		)
		(fp_line
			(start -2.351 4.498)
			(end -2.351 -3.5)
			(stroke
				(width 0.15)
				(type solid)
			)
			(layer "F.Fab")
		)
		(fp_line
			(start -1.351 -4.5)
			(end 2.35 -4.5)
			(stroke
				(width 0.15)
				(type solid)
			)
			(layer "F.Fab")
		)
		(fp_line
			(start -1 -3.75)
			(end -1 -3.25)
			(stroke
				(width 0.15)
				(type solid)
			)
			(layer "F.Fab")
		)
		(fp_line
			(start -1 -3.65)
			(end -0.335 -3.65)
			(stroke
				(width 0.15)
				(type solid)
			)
			(layer "F.Fab")
		)
		(fp_line
			(start -1 -3.551)
			(end -0.335 -3.551)
			(stroke
				(width 0.15)
				(type solid)
			)
			(layer "F.Fab")
		)
		(fp_line
			(start -1 -3.451)
			(end -0.335 -3.451)
			(stroke
				(width 0.15)
				(type solid)
			)
			(layer "F.Fab")
		)
		(fp_line
			(start -1 -3.351)
			(end -0.335 -3.351)
			(stroke
				(width 0.15)
				(type solid)
			)
			(layer "F.Fab")
		)
		(fp_line
			(start -1 -3.25)
			(end 0.998 -3.25)
			(stroke
				(width 0.15)
				(type solid)
			)
			(layer "F.Fab")
		)
		(fp_line
			(start -1 -2.75)
			(end -1 -2.25)
			(stroke
				(width 0.15)
				(type solid)
			)
			(layer "F.Fab")
		)
		(fp_line
			(start -1 -2.65)
			(end -0.335 -2.65)
			(stroke
				(width 0.15)
				(type solid)
			)
			(layer "F.Fab")
		)
		(fp_line
			(start -1 -2.551)
			(end -0.335 -2.551)
			(stroke
				(width 0.15)
				(type solid)
			)
			(layer "F.Fab")
		)
		(fp_line
			(start -1 -2.452)
			(end -0.335 -2.452)
			(stroke
				(width 0.15)
				(type solid)
			)
			(layer "F.Fab")
		)
		(fp_line
			(start -1 -2.351)
			(end -0.335 -2.351)
			(stroke
				(width 0.15)
				(type solid)
			)
			(layer "F.Fab")
		)
		(fp_line
			(start -1 -2.25)
			(end 0.998 -2.25)
			(stroke
				(width 0.15)
				(type solid)
			)
			(layer "F.Fab")
		)
		(fp_line
			(start -1 -1.75)
			(end -1 -1.25)
			(stroke
				(width 0.15)
				(type solid)
			)
			(layer "F.Fab")
		)
		(fp_line
			(start -1 -1.651)
			(end -0.335 -1.651)
			(stroke
				(width 0.15)
				(type solid)
			)
			(layer "F.Fab")
		)
		(fp_line
			(start -1 -1.551)
			(end -0.335 -1.551)
			(stroke
				(width 0.15)
				(type solid)
			)
			(layer "F.Fab")
		)
		(fp_line
			(start -1 -1.45)
			(end -0.335 -1.45)
			(stroke
				(width 0.15)
				(type solid)
			)
			(layer "F.Fab")
		)
		(fp_line
			(start -1 -1.351)
			(end -0.335 -1.351)
			(stroke
				(width 0.15)
				(type solid)
			)
			(layer "F.Fab")
		)
		(fp_line
			(start -1 -1.25)
			(end 0.998 -1.25)
			(stroke
				(width 0.15)
				(type solid)
			)
			(layer "F.Fab")
		)
		(fp_line
			(start -1 -0.75)
			(end -1 -0.25)
			(stroke
				(width 0.15)
				(type solid)
			)
			(layer "F.Fab")
		)
		(fp_line
			(start -1 -0.652)
			(end -0.335 -0.652)
			(stroke
				(width 0.15)
				(type solid)
			)
			(layer "F.Fab")
		)
		(fp_line
			(start -1 -0.552)
			(end -0.335 -0.552)
			(stroke
				(width 0.15)
				(type solid)
			)
			(layer "F.Fab")
		)
		(fp_line
			(start -1 -0.452)
			(end -0.335 -0.452)
			(stroke
				(width 0.15)
				(type solid)
			)
			(layer "F.Fab")
		)
		(fp_line
			(start -1 -0.351)
			(end -0.335 -0.351)
			(stroke
				(width 0.15)
				(type solid)
			)
			(layer "F.Fab")
		)
		(fp_line
			(start -1 -0.25)
			(end 0.998 -0.25)
			(stroke
				(width 0.15)
				(type solid)
			)
			(layer "F.Fab")
		)
		(fp_line
			(start -1 0.248)
			(end -1 0.748)
			(stroke
				(width 0.15)
				(type solid)
			)
			(layer "F.Fab")
		)
		(fp_line
			(start -1 0.349)
			(end -0.335 0.349)
			(stroke
				(width 0.15)
				(type solid)
			)
			(layer "F.Fab")
		)
		(fp_line
			(start -1 0.45)
			(end -0.335 0.45)
			(stroke
				(width 0.15)
				(type solid)
			)
			(layer "F.Fab")
		)
		(fp_line
			(start -1 0.55)
			(end -0.335 0.55)
			(stroke
				(width 0.15)
				(type solid)
			)
			(layer "F.Fab")
		)
		(fp_line
			(start -1 0.65)
			(end -0.335 0.65)
			(stroke
				(width 0.15)
				(type solid)
			)
			(layer "F.Fab")
		)
		(fp_line
			(start -1 0.748)
			(end -0.335 0.748)
			(stroke
				(width 0.15)
				(type solid)
			)
			(layer "F.Fab")
		)
		(fp_line
			(start -1 0.748)
			(end 0.998 0.748)
			(stroke
				(width 0.15)
				(type solid)
			)
			(layer "F.Fab")
		)
		(fp_line
			(start -1 1.249)
			(end -1 1.749)
			(stroke
				(width 0.15)
				(type solid)
			)
			(layer "F.Fab")
		)
		(fp_line
			(start -1 1.35)
			(end -0.335 1.35)
			(stroke
				(width 0.15)
				(type solid)
			)
			(layer "F.Fab")
		)
		(fp_line
			(start -1 1.449)
			(end -0.335 1.449)
			(stroke
				(width 0.15)
				(type solid)
			)
			(layer "F.Fab")
		)
		(fp_line
			(start -1 1.55)
			(end -0.335 1.55)
			(stroke
				(width 0.15)
				(type solid)
			)
			(layer "F.Fab")
		)
		(fp_line
			(start -1 1.648)
			(end -0.335 1.648)
			(stroke
				(width 0.15)
				(type solid)
			)
			(layer "F.Fab")
		)
		(fp_line
			(start -1 1.749)
			(end -0.335 1.749)
			(stroke
				(width 0.15)
				(type solid)
			)
			(layer "F.Fab")
		)
		(fp_line
			(start -1 1.749)
			(end 0.998 1.749)
			(stroke
				(width 0.15)
				(type solid)
			)
			(layer "F.Fab")
		)
		(fp_line
			(start -1 2.249)
			(end -1 2.749)
			(stroke
				(width 0.15)
				(type solid)
			)
			(layer "F.Fab")
		)
		(fp_line
			(start -1 2.35)
			(end -0.335 2.35)
			(stroke
				(width 0.15)
				(type solid)
			)
			(layer "F.Fab")
		)
		(fp_line
			(start -1 2.45)
			(end -0.335 2.45)
			(stroke
				(width 0.15)
				(type solid)
			)
			(layer "F.Fab")
		)
		(fp_line
			(start -1 2.548)
			(end -0.335 2.548)
			(stroke
				(width 0.15)
				(type solid)
			)
			(layer "F.Fab")
		)
		(fp_line
			(start -1 2.648)
			(end -0.335 2.648)
			(stroke
				(width 0.15)
				(type solid)
			)
			(layer "F.Fab")
		)
		(fp_line
			(start -1 2.749)
			(end -0.335 2.749)
			(stroke
				(width 0.15)
				(type solid)
			)
			(layer "F.Fab")
		)
		(fp_line
			(start -1 2.749)
			(end 0.998 2.749)
			(stroke
				(width 0.15)
				(type solid)
			)
			(layer "F.Fab")
		)
		(fp_line
			(start -1 3.249)
			(end -1 3.749)
			(stroke
				(width 0.15)
				(type solid)
			)
			(layer "F.Fab")
		)
		(fp_line
			(start -1 3.35)
			(end -0.335 3.35)
			(stroke
				(width 0.15)
				(type solid)
			)
			(layer "F.Fab")
		)
		(fp_line
			(start -1 3.45)
			(end -0.335 3.45)
			(stroke
				(width 0.15)
				(type solid)
			)
			(layer "F.Fab")
		)
		(fp_line
			(start -1 3.548)
			(end -0.335 3.548)
			(stroke
				(width 0.15)
				(type solid)
			)
			(layer "F.Fab")
		)
		(fp_line
			(start -1 3.648)
			(end -0.335 3.648)
			(stroke
				(width 0.15)
				(type solid)
			)
			(layer "F.Fab")
		)
		(fp_line
			(start -1 3.749)
			(end -0.335 3.749)
			(stroke
				(width 0.15)
				(type solid)
			)
			(layer "F.Fab")
		)
		(fp_line
			(start -1 3.749)
			(end 0.998 3.749)
			(stroke
				(width 0.15)
				(type solid)
			)
			(layer "F.Fab")
		)
		(fp_line
			(start -0.335 -3.75)
			(end -0.335 -3.25)
			(stroke
				(width 0.15)
				(type solid)
			)
			(layer "F.Fab")
		)
		(fp_line
			(start -0.335 -2.75)
			(end -0.335 -2.25)
			(stroke
				(width 0.15)
				(type solid)
			)
			(layer "F.Fab")
		)
		(fp_line
			(start -0.335 -1.75)
			(end -0.335 -1.25)
			(stroke
				(width 0.15)
				(type solid)
			)
			(layer "F.Fab")
		)
		(fp_line
			(start -0.335 -0.75)
			(end -0.335 -0.25)
			(stroke
				(width 0.15)
				(type solid)
			)
			(layer "F.Fab")
		)
		(fp_line
			(start -0.335 0.248)
			(end -0.335 0.748)
			(stroke
				(width 0.15)
				(type solid)
			)
			(layer "F.Fab")
		)
		(fp_line
			(start -0.335 1.249)
			(end -0.335 1.749)
			(stroke
				(width 0.15)
				(type solid)
			)
			(layer "F.Fab")
		)
		(fp_line
			(start -0.335 2.249)
			(end -0.335 2.749)
			(stroke
				(width 0.15)
				(type solid)
			)
			(layer "F.Fab")
		)
		(fp_line
			(start -0.335 3.249)
			(end -0.335 3.749)
			(stroke
				(width 0.15)
				(type solid)
			)
			(layer "F.Fab")
		)
		(fp_line
			(start 0.998 -3.75)
			(end -1 -3.75)
			(stroke
				(width 0.15)
				(type solid)
			)
			(layer "F.Fab")
		)
		(fp_line
			(start 0.998 -3.25)
			(end 0.998 -3.75)
			(stroke
				(width 0.15)
				(type solid)
			)
			(layer "F.Fab")
		)
		(fp_line
			(start 0.998 -2.75)
			(end -1 -2.75)
			(stroke
				(width 0.15)
				(type solid)
			)
			(layer "F.Fab")
		)
		(fp_line
			(start 0.998 -2.25)
			(end 0.998 -2.75)
			(stroke
				(width 0.15)
				(type solid)
			)
			(layer "F.Fab")
		)
		(fp_line
			(start 0.998 -1.75)
			(end -1 -1.75)
			(stroke
				(width 0.15)
				(type solid)
			)
			(layer "F.Fab")
		)
		(fp_line
			(start 0.998 -1.25)
			(end 0.998 -1.75)
			(stroke
				(width 0.15)
				(type solid)
			)
			(layer "F.Fab")
		)
		(fp_line
			(start 0.998 -0.75)
			(end -1 -0.75)
			(stroke
				(width 0.15)
				(type solid)
			)
			(layer "F.Fab")
		)
		(fp_line
			(start 0.998 -0.25)
			(end 0.998 -0.75)
			(stroke
				(width 0.15)
				(type solid)
			)
			(layer "F.Fab")
		)
		(fp_line
			(start 0.998 0.248)
			(end -1 0.248)
			(stroke
				(width 0.15)
				(type solid)
			)
			(layer "F.Fab")
		)
		(fp_line
			(start 0.998 0.748)
			(end 0.998 0.248)
			(stroke
				(width 0.15)
				(type solid)
			)
			(layer "F.Fab")
		)
		(fp_line
			(start 0.998 1.249)
			(end -1 1.249)
			(stroke
				(width 0.15)
				(type solid)
			)
			(layer "F.Fab")
		)
		(fp_line
			(start 0.998 1.749)
			(end 0.998 1.249)
			(stroke
				(width 0.15)
				(type solid)
			)
			(layer "F.Fab")
		)
		(fp_line
			(start 0.998 2.249)
			(end -1 2.249)
			(stroke
				(width 0.15)
				(type solid)
			)
			(layer "F.Fab")
		)
		(fp_line
			(start 0.998 2.749)
			(end 0.998 2.249)
			(stroke
				(width 0.15)
				(type solid)
			)
			(layer "F.Fab")
		)
		(fp_line
			(start 0.998 3.249)
			(end -1 3.249)
			(stroke
				(width 0.15)
				(type solid)
			)
			(layer "F.Fab")
		)
		(fp_line
			(start 0.998 3.749)
			(end 0.998 3.249)
			(stroke
				(width 0.15)
				(type solid)
			)
			(layer "F.Fab")
		)
		(fp_line
			(start 2.35 -4.5)
			(end 2.35 4.498)
			(stroke
				(width 0.15)
				(type solid)
			)
			(layer "F.Fab")
		)
		(fp_line
			(start 2.35 4.498)
			(end -2.351 4.498)
			(stroke
				(width 0.15)
				(type solid)
			)
			(layer "F.Fab")
		)
		(fp_text user "on"
			(at -1.56 0.69 90)
			(layer "F.Fab")
			(effects
				(font
					(size 0.7 0.7)
					(thickness 0.15)
				)
				(justify left bottom)
			)
		)
		(pad "1" smd rect
			(at -2.952 -3.5)
			(size 1.2 0.5)
			(layers "F.Cu" "F.Mask" "F.Paste")
			(net 186 "/Supply/PB_CTRL_OUT")
			(pinfunction "1")
			(pintype "passive")
		)
		(pad "2" smd rect
			(at -2.952 -2.5)
			(size 1.2 0.5)
			(layers "F.Cu" "F.Mask" "F.Paste")
			(net 207 "/Supply/~{PB_CTRL_INT}")
			(pinfunction "2")
			(pintype "passive")
		)
		(pad "3" smd rect
			(at -2.952 -1.5)
			(size 1.2 0.5)
			(layers "F.Cu" "F.Mask" "F.Paste")
			(net 686 "IN1")
			(pinfunction "3")
			(pintype "passive")
		)
		(pad "4" smd rect
			(at -2.952 -0.5)
			(size 1.2 0.5)
			(layers "F.Cu" "F.Mask" "F.Paste")
			(net 687 "IN2")
			(pinfunction "4")
			(pintype "passive")
		)
		(pad "5" smd rect
			(at -2.952 0.498)
			(size 1.2 0.5)
			(layers "F.Cu" "F.Mask" "F.Paste")
			(net 690 "/I^{2}C/PWR.SDA")
			(pinfunction "5")
			(pintype "passive")
		)
		(pad "6" smd rect
			(at -2.952 1.499)
			(size 1.2 0.5)
			(layers "F.Cu" "F.Mask" "F.Paste")
			(net 691 "/I^{2}C/PWR.SCL")
			(pinfunction "6")
			(pintype "passive")
		)
		(pad "7" smd rect
			(at -2.952 2.499)
			(size 1.2 0.5)
			(layers "F.Cu" "F.Mask" "F.Paste")
			(net 691 "/I^{2}C/PWR.SCL")
			(pinfunction "7")
			(pintype "passive")
		)
		(pad "8" smd rect
			(at -2.952 3.499)
			(size 1.2 0.5)
			(layers "F.Cu" "F.Mask" "F.Paste")
			(net 263 "FTDI_DIS")
			(pinfunction "8")
			(pintype "passive")
		)
		(pad "9" smd rect
			(at 2.95 3.499)
			(size 1.2 0.5)
			(layers "F.Cu" "F.Mask" "F.Paste")
			(net 1 "GND")
			(pinfunction "9")
			(pintype "passive")
		)
		(pad "10" smd rect
			(at 2.95 2.499)
			(size 1.2 0.5)
			(layers "F.Cu" "F.Mask" "F.Paste")
			(net 285 "/Supply/QDCDC2_SCL")
			(pinfunction "10")
			(pintype "passive")
		)
		(pad "11" smd rect
			(at 2.95 1.499)
			(size 1.2 0.5)
			(layers "F.Cu" "F.Mask" "F.Paste")
			(net 297 "/Supply/PWR_SCL_2")
			(pinfunction "11")
			(pintype "passive")
		)
		(pad "12" smd rect
			(at 2.95 0.498)
			(size 1.2 0.5)
			(layers "F.Cu" "F.Mask" "F.Paste")
			(net 298 "/Supply/PWR_SDA_2")
			(pinfunction "12")
			(pintype "passive")
		)
		(pad "13" smd rect
			(at 2.95 -0.5)
			(size 1.2 0.5)
			(layers "F.Cu" "F.Mask" "F.Paste")
			(net 1 "GND")
			(pinfunction "13")
			(pintype "passive")
		)
		(pad "14" smd rect
			(at 2.95 -1.5)
			(size 1.2 0.5)
			(layers "F.Cu" "F.Mask" "F.Paste")
			(net 1 "GND")
			(pinfunction "14")
			(pintype "passive")
		)
		(pad "15" smd rect
			(at 2.95 -2.5)
			(size 1.2 0.5)
			(layers "F.Cu" "F.Mask" "F.Paste")
			(net 185 "/Supply/~{PB_CTRL_CLR}")
			(pinfunction "15")
			(pintype "passive")
		)
		(pad "16" smd rect
			(at 2.95 -3.5)
			(size 1.2 0.5)
			(layers "F.Cu" "F.Mask" "F.Paste")
			(net 62 "/Supply/SEQ_EN")
			(pinfunction "16")
			(pintype "passive")
		)
		(pad "17" smd rect
			(at -2.15 -4.5)
			(size 0.7 0.7)
			(layers "F.Cu" "F.Mask" "F.Paste")
			(net 1 "GND")
			(pinfunction "17")
			(pintype "power_in")
		)
		(pad "17" smd rect
			(at -2.15 4.498)
			(size 0.7 0.7)
			(layers "F.Cu" "F.Mask" "F.Paste")
			(net 1 "GND")
			(pinfunction "17")
			(pintype "power_in")
		)
		(pad "17" smd rect
			(at 2.148 -4.5)
			(size 0.7 0.7)
			(layers "F.Cu" "F.Mask" "F.Paste")
			(net 1 "GND")
			(pinfunction "17")
			(pintype "power_in")
		)
		(pad "17" smd rect
			(at 2.148 4.498)
			(size 0.7 0.7)
			(layers "F.Cu" "F.Mask" "F.Paste")
			(net 1 "GND")
			(pinfunction "17")
			(pintype "power_in")
		)
	)
	(footprint "antmicro-footprints:Heatsink_960-27-12-D-AB-0"
		(layer "F.Cu")
		(at 138.880501 174.811 90)
		(descr "27mm x 27mm Heat Sink, BGA, Black Anodized Aluminum, Top Mount, Push Pin")
		(property "Reference" "H1"
			(at 0 -21.8 90)
			(unlocked yes)
			(layer "F.SilkS")
			(hide yes)
			(effects
				(font
					(size 0.7 0.7)
					(thickness 0.15)
				)
				(justify left bottom)
			)
		)
		(property "Value" "Heatsink_960-27-12-D-AB-0"
			(at 0 22.6 90)
			(unlocked yes)
			(layer "F.Fab")
			(effects
				(font
					(size 0.7 0.7)
					(thickness 0.15)
				)
				(justify left bottom)
			)
		)
		(property "Datasheet" "https://media.digikey.com/pdf/Data%20Sheets/Wakefield%20Thermal%20PDFs/960_Series.pdf"
			(at 0 0 90)
			(layer "F.Fab")
			(hide yes)
			(effects
				(font
					(size 1.27 1.27)
					(thickness 0.15)
				)
			)
		)
		(property "Author" "Antmicro"
			(at 313.691501 35.930499 0)
			(layer "F.Fab")
			(hide yes)
			(effects
				(font
					(size 1 1)
					(thickness 0.15)
				)
			)
		)
		(property "License" "Apache-2.0"
			(at 313.691501 35.930499 0)
			(layer "F.Fab")
			(hide yes)
			(effects
				(font
					(size 1 1)
					(thickness 0.15)
				)
			)
		)
		(property "MPN" "960-27-12-D-AB-0"
			(at 313.691501 35.930499 0)
			(layer "F.Fab")
			(hide yes)
			(effects
				(font
					(size 1 1)
					(thickness 0.15)
				)
			)
		)
		(property "Manufacturer" "Wakefield-Vette"
			(at 313.691501 35.930499 0)
			(layer "F.Fab")
			(hide yes)
			(effects
				(font
					(size 1 1)
					(thickness 0.15)
				)
			)
		)
		(property ki_fp_filters "Heatsink_*")
		(sheetname "/")
		(sheetfile "sodimm-ddr5-tester.kicad_sch")
		(attr through_hole exclude_from_pos_files exclude_from_bom dnp)
		(fp_rect
			(start -21.35 -21.35)
			(end 21.36 21.35)
			(stroke
				(width 0.05)
				(type solid)
			)
			(fill no)
			(layer "F.CrtYd")
		)
		(fp_circle
			(center 16.91 -16.93)
			(end 19.46 -16.93)
			(stroke
				(width 0.05)
				(type solid)
			)
			(fill no)
			(layer "F.CrtYd")
		)
		(fp_circle
			(center -16.92 16.92)
			(end -14.38 16.92)
			(stroke
				(width 0.05)
				(type solid)
			)
			(fill no)
			(layer "F.CrtYd")
		)
		(pad "" np_thru_hole circle
			(at -16.92 16.925 90)
			(size 3.18 3.18)
			(drill 3.18)
			(layers "*.Cu" "*.Mask")
		)
		(pad "" np_thru_hole circle
			(at 16.93 -16.925 90)
			(size 3.18 3.18)
			(drill 3.18)
			(layers "*.Cu" "*.Mask")
		)
	)
)
